FILE_TYPE=LIBRARY_PARTS;
primitive 'RAA229126GNPHA0';
  pin
    'CS11':
      PIN_NUMBER='(27)';
      INPUT_LOAD='(-0.01,0.01)';
    'VCC':
      PIN_NUMBER='(47)';
      PINUSE='POWER';
      NO_LOAD_CHECK='Both';
      NO_IO_CHECK='Both';
      NO_ASSERT_CHECK='TRUE';
      NO_DIR_CHECK='TRUE';
      ALLOW_CONNECT='TRUE';
    'EN1':
      PIN_NUMBER='(24)';
      INPUT_LOAD='(-0.01,0.01)';
    'PMSCL':
      PIN_NUMBER='(14)';
      INPUT_LOAD='(-0.01,0.01)';
    'SVDATA':
      PIN_NUMBER='(22)';
      BIDIRECTIONAL='TRUE';
      INPUT_LOAD='(-0.01,0.01)';
      OUTPUT_LOAD='(1.0,-1.0)';
    'CS6':
      PIN_NUMBER='(32)';
      INPUT_LOAD='(-0.01,0.01)';
    'NSVALERT':
      PIN_NUMBER='(23)';
      OUTPUT_LOAD='(1.0,-1.0)';
    'NVRHOT':
      PIN_NUMBER='(18)';
      OUTPUT_LOAD='(1.0,-1.0)';
    'CS5':
      PIN_NUMBER='(33)';
      INPUT_LOAD='(-0.01,0.01)';
    'CS4':
      PIN_NUMBER='(34)';
      INPUT_LOAD='(-0.01,0.01)';
    'PG1':
      PIN_NUMBER='(20)';
      OUTPUT_LOAD='(1.0,-1.0)';
    'SVCLK':
      PIN_NUMBER='(21)';
      INPUT_LOAD='(-0.01,0.01)';
    'NPMALERT':
      PIN_NUMBER='(15)';
      OUTPUT_LOAD='(1.0,-1.0)';
    'EN0':
      PIN_NUMBER='(17)';
      INPUT_LOAD='(-0.01,0.01)';
    'RGND0':
      PIN_NUMBER='(26)';
      INPUT_LOAD='(-0.01,0.01)';
    'PMSDA':
      PIN_NUMBER='(13)';
      BIDIRECTIONAL='TRUE';
      INPUT_LOAD='(-0.01,0.01)';
      OUTPUT_LOAD='(1.0,-1.0)';
    'PWM4':
      PIN_NUMBER='(5)';
      OUTPUT_LOAD='(1.0,-1.0)';
    'PWM5':
      PIN_NUMBER='(6)';
      OUTPUT_LOAD='(1.0,-1.0)';
    'VSEN0':
      PIN_NUMBER='(25)';
      INPUT_LOAD='(-0.01,0.01)';
    'PWM1':
      PIN_NUMBER='(2)';
      OUTPUT_LOAD='(1.0,-1.0)';
    'PG0':
      PIN_NUMBER='(16)';
      OUTPUT_LOAD='(1.0,-1.0)';
    'PWM6':
      PIN_NUMBER='(7)';
      OUTPUT_LOAD='(1.0,-1.0)';
    'VCCS':
      PIN_NUMBER='(48)';
      PINUSE='POWER';
      NO_LOAD_CHECK='Both';
      NO_IO_CHECK='Both';
      NO_ASSERT_CHECK='TRUE';
      NO_DIR_CHECK='TRUE';
      ALLOW_CONNECT='TRUE';
    'VMON||IINSEN||VSYS||ISYS':
      PIN_NUMBER='(45)';
      INPUT_LOAD='(-0.01,0.01)';
    'VINSEN||VSYS':
      PIN_NUMBER='(46)';
      INPUT_LOAD='(-0.01,0.01)';
    'TEMP1||ISYS':
      PIN_NUMBER='(44)';
      INPUT_LOAD='(-0.01,0.01)';
    'NPINALERT||NPSYS_CRIT':
      PIN_NUMBER='(19)';
      OUTPUT_LOAD='(1.0,-1.0)';
    'VSEN1':
      PIN_NUMBER='(40)';
      INPUT_LOAD='(-0.01,0.01)';
    'RGND1':
      PIN_NUMBER='(39)';
      INPUT_LOAD='(-0.01,0.01)';
    'CS1':
      PIN_NUMBER='(37)';
      INPUT_LOAD='(-0.01,0.01)';
    'PWM11':
      PIN_NUMBER='(12)';
      OUTPUT_LOAD='(1.0,-1.0)';
    'PWM3':
      PIN_NUMBER='(4)';
      OUTPUT_LOAD='(1.0,-1.0)';
    'CS3':
      PIN_NUMBER='(35)';
      INPUT_LOAD='(-0.01,0.01)';
    'PWM2':
      PIN_NUMBER='(3)';
      OUTPUT_LOAD='(1.0,-1.0)';
    'CS2':
      PIN_NUMBER='(36)';
      INPUT_LOAD='(-0.01,0.01)';
    'CFP':
      PIN_NUMBER='(41)';
      OUTPUT_LOAD='(1.0,-1.0)';
    'TH_GND':
      PIN_NUMBER='(TH)';
      PINUSE='POWER';
      NO_LOAD_CHECK='Both';
      NO_IO_CHECK='Both';
      NO_ASSERT_CHECK='TRUE';
      NO_DIR_CHECK='TRUE';
      ALLOW_CONNECT='TRUE';
    'ADDR_CFG':
      PIN_NUMBER='(42)';
      INPUT_LOAD='(-0.01,0.01)';
    'TEMP0':
      PIN_NUMBER='(43)';
      INPUT_LOAD='(-0.01,0.01)';
    'PWM0':
      PIN_NUMBER='(1)';
      OUTPUT_LOAD='(1.0,-1.0)';
    'CS0':
      PIN_NUMBER='(38)';
      INPUT_LOAD='(-0.01,0.01)';
    'PWM7':
      PIN_NUMBER='(8)';
      OUTPUT_LOAD='(1.0,-1.0)';
    'CS7':
      PIN_NUMBER='(31)';
      INPUT_LOAD='(-0.01,0.01)';
    'PWM8':
      PIN_NUMBER='(9)';
      OUTPUT_LOAD='(1.0,-1.0)';
    'CS8':
      PIN_NUMBER='(30)';
      INPUT_LOAD='(-0.01,0.01)';
    'PWM9':
      PIN_NUMBER='(10)';
      OUTPUT_LOAD='(1.0,-1.0)';
    'CS9':
      PIN_NUMBER='(29)';
      INPUT_LOAD='(-0.01,0.01)';
    'PWM10':
      PIN_NUMBER='(11)';
      OUTPUT_LOAD='(1.0,-1.0)';
    'CS10':
      PIN_NUMBER='(28)';
      INPUT_LOAD='(-0.01,0.01)';
  end_pin;
  body
    PART_NAME='RAA229126GNPHA0';
    BODY_NAME='RAA229126GNPHA0';
    PHYS_DES_PREFIX='U';
    CLASS='IC';
  end_body;
end_primitive;

END.
